(kicad_pcb
	(version 20241229)
	(generator "pcbnew")
	(generator_version "9.0")
	(general
		(thickness 1.6296)
		(legacy_teardrops no)
	)
	(paper "A3")
	(title_block
		(title "Thunderbolt to 10GbE adapter")
		(date "2026-04-21")
		(rev "1.1.0")
		(company "Antmicro Ltd")
		(comment 1 "www.antmicro.com")
		(comment 9 "footprints 81-84 of 703")
	)
	(layers
		(0 "F.Cu" signal)
		(4 "In1.Cu" signal)
		(6 "In2.Cu" signal)
		(8 "In3.Cu" signal)
		(10 "In4.Cu" signal)
		(12 "In5.Cu" signal)
		(14 "In6.Cu" signal)
		(2 "B.Cu" signal)
		(9 "F.Adhes" user "F.Adhesive")
		(11 "B.Adhes" user "B.Adhesive")
		(13 "F.Paste" user)
		(15 "B.Paste" user)
		(5 "F.SilkS" user "F.Silkscreen")
		(7 "B.SilkS" user "B.Silkscreen")
		(1 "F.Mask" user)
		(3 "B.Mask" user)
		(17 "Dwgs.User" user "User.Drawings")
		(19 "Cmts.User" user "User.Comments")
		(21 "Eco1.User" user "User.Eco1")
		(23 "Eco2.User" user "User.Eco2")
		(25 "Edge.Cuts" user)
		(27 "Margin" user)
		(31 "F.CrtYd" user "F.Courtyard")
		(29 "B.CrtYd" user "B.Courtyard")
		(35 "F.Fab" user)
		(33 "B.Fab" user)
	)
	(footprint "antmicro-footprints:C_0603_1608Metric_EIA"
		(layer "F.Cu")
		(at 136.005 89.274999 -90)
		(descr "Capacitor SMD 0603, IPC-7351 Density Level A")
		(tags "Capacitor 0603")
		(property "Reference" "C249"
			(at 4.225001 16.7 270)
			(layer "F.SilkS")
			(effects
				(font
					(size 0.7 0.7)
					(thickness 0.15)
				)
				(justify left bottom)
			)
		)
		(property "Value" "C_22u_16V_0603"
			(at -1.42757 1.770288 270)
			(layer "F.Fab")
			(effects
				(font
					(size 0.7 0.7)
					(thickness 0.15)
				)
				(justify left bottom)
			)
		)
		(property "Datasheet" "https://product.samsungsem.com/mlcc/CL10A226MO7JZN.do"
			(at 0 0 270)
			(layer "F.Fab")
			(hide yes)
			(effects
				(font
					(size 1.27 1.27)
					(thickness 0.15)
				)
			)
		)
		(property "Description" "SMD Multilayer Ceramic Capacitor"
			(at 0 0 270)
			(layer "F.Fab")
			(hide yes)
			(effects
				(font
					(size 1.27 1.27)
					(thickness 0.15)
				)
			)
		)
		(property "MPN" "CL10A226MO7JZNC"
			(at 0 0 270)
			(unlocked yes)
			(layer "F.Fab")
			(hide yes)
			(effects
				(font
					(size 1 1)
					(thickness 0.15)
				)
			)
		)
		(property "Manufacturer" "Samsung Electro-Mechanics"
			(at 0 0 270)
			(unlocked yes)
			(layer "F.Fab")
			(hide yes)
			(effects
				(font
					(size 1 1)
					(thickness 0.15)
				)
			)
		)
		(property "License" "Apache-2.0"
			(at 0 0 270)
			(unlocked yes)
			(layer "F.Fab")
			(hide yes)
			(effects
				(font
					(size 1 1)
					(thickness 0.15)
				)
			)
		)
		(property "Author" "Antmicro"
			(at 0 0 270)
			(unlocked yes)
			(layer "F.Fab")
			(hide yes)
			(effects
				(font
					(size 1 1)
					(thickness 0.15)
				)
			)
		)
		(property "Val" "22u"
			(at 0 0 270)
			(unlocked yes)
			(layer "F.Fab")
			(hide yes)
			(effects
				(font
					(size 1 1)
					(thickness 0.15)
				)
			)
		)
		(property "Voltage" "16V"
			(at 0 0 270)
			(unlocked yes)
			(layer "F.Fab")
			(hide yes)
			(effects
				(font
					(size 1 1)
					(thickness 0.15)
				)
			)
		)
		(property "Dielectric" ""
			(at 0 0 270)
			(unlocked yes)
			(layer "F.Fab")
			(hide yes)
			(effects
				(font
					(size 1 1)
					(thickness 0.15)
				)
			)
		)
		(sheetname "/X710-AT2 power/")
		(sheetfile "x710-at2-power.kicad_sch")
		(attr smd)
		(fp_line
			(start -0.15 0.55)
			(end 0.15 0.55)
			(stroke
				(width 0.15)
				(type solid)
			)
			(layer "F.SilkS")
		)
		(fp_line
			(start -0.15 -0.55)
			(end 0.15 -0.55)
			(stroke
				(width 0.15)
				(type solid)
			)
			(layer "F.SilkS")
		)
		(fp_rect
			(start -1.25 -0.65)
			(end 1.25 0.65)
			(stroke
				(width 0.05)
				(type solid)
			)
			(fill no)
			(layer "F.CrtYd")
		)
		(fp_rect
			(start -0.8 -0.45)
			(end 0.8 0.45)
			(stroke
				(width 0.15)
				(type solid)
			)
			(fill no)
			(layer "F.Fab")
		)
		(fp_text user "Author: Antmicro"
			(at -1.682 4.894 270)
			(layer "F.Fab")
			(effects
				(font
					(size 0.7 0.7)
					(thickness 0.15)
				)
				(justify left bottom)
			)
		)
		(fp_text user "License: Apache-2.0"
			(at -1.682 5.895 270)
			(layer "F.Fab")
			(effects
				(font
					(size 0.7 0.7)
					(thickness 0.15)
				)
				(justify left bottom)
			)
		)
		(fp_text user "${REFERENCE}"
			(at -1.682 3.895 270)
			(layer "F.Fab")
			(effects
				(font
					(size 0.7 0.7)
					(thickness 0.15)
				)
				(justify left bottom)
			)
		)
		(pad "1" smd roundrect
			(at -0.7 0 270)
			(size 0.8 1.1)
			(layers "F.Cu" "F.Mask" "F.Paste")
			(roundrect_rratio 0.2)
			(net 23 "GND")
			(pintype "passive")
		)
		(pad "2" smd roundrect
			(at 0.7 0 270)
			(size 0.8 1.1)
			(layers "F.Cu" "F.Mask" "F.Paste")
			(roundrect_rratio 0.2)
			(net 7 "+3V3")
			(pintype "passive")
		)
	)
	(footprint "antmicro-footprints:SOD-523"
		(layer "F.Cu")
		(at 134 59.2 180)
		(property "Reference" "D17"
			(at 3.6 -0.4 180)
			(layer "F.SilkS")
			(effects
				(font
					(size 0.7 0.7)
					(thickness 0.15)
				)
				(justify left bottom)
			)
		)
		(property "Value" "PESD5Z5.0F"
			(at 0 1.499 180)
			(layer "F.Fab")
			(effects
				(font
					(size 0.7 0.7)
					(thickness 0.15)
				)
				(justify left bottom)
			)
		)
		(property "Datasheet" "https://assets.nexperia.com/documents/data-sheet/PESD5Z5_0.pdf"
			(at 0 0 180)
			(layer "F.Fab")
			(hide yes)
			(effects
				(font
					(size 1.27 1.27)
					(thickness 0.15)
				)
			)
		)
		(property "Description" "Unidirectional TVS, 30 kV,  SOD-523, 5 V, 89 pF"
			(at 0 0 180)
			(layer "F.Fab")
			(hide yes)
			(effects
				(font
					(size 1.27 1.27)
					(thickness 0.15)
				)
			)
		)
		(property "Manufacturer" "Nexperia"
			(at 0 0 180)
			(unlocked yes)
			(layer "F.Fab")
			(hide yes)
			(effects
				(font
					(size 1 1)
					(thickness 0.15)
				)
			)
		)
		(property "MPN" "PESD5Z5.0F"
			(at 0 0 180)
			(unlocked yes)
			(layer "F.Fab")
			(hide yes)
			(effects
				(font
					(size 1 1)
					(thickness 0.15)
				)
			)
		)
		(property "Author" "Antmicro"
			(at 0 0 180)
			(unlocked yes)
			(layer "F.Fab")
			(hide yes)
			(effects
				(font
					(size 1 1)
					(thickness 0.15)
				)
			)
		)
		(property "License" "Apache-2.0"
			(at 0 0 180)
			(unlocked yes)
			(layer "F.Fab")
			(hide yes)
			(effects
				(font
					(size 1 1)
					(thickness 0.15)
				)
			)
		)
		(sheetname "/Power input/")
		(sheetfile "power_input.kicad_sch")
		(attr smd)
		(fp_line
			(start -0.35 -0.5)
			(end -0.35 0.5)
			(stroke
				(width 0.15)
				(type solid)
			)
			(layer "F.SilkS")
		)
		(fp_rect
			(start -1 -0.6)
			(end 1 0.6)
			(stroke
				(width 0.05)
				(type solid)
			)
			(fill no)
			(layer "F.CrtYd")
		)
		(fp_line
			(start 0.65 -0.425)
			(end 0.65 0.423)
			(stroke
				(width 0.15)
				(type solid)
			)
			(layer "F.Fab")
		)
		(fp_line
			(start -0.35 -0.4)
			(end -0.35 0.4)
			(stroke
				(width 0.15)
				(type solid)
			)
			(layer "F.Fab")
		)
		(fp_line
			(start -0.652 0.423)
			(end 0.65 0.423)
			(stroke
				(width 0.15)
				(type solid)
			)
			(layer "F.Fab")
		)
		(fp_line
			(start -0.652 0.423)
			(end -0.652 -0.425)
			(stroke
				(width 0.15)
				(type solid)
			)
			(layer "F.Fab")
		)
		(fp_line
			(start -0.652 -0.425)
			(end 0.65 -0.425)
			(stroke
				(width 0.15)
				(type solid)
			)
			(layer "F.Fab")
		)
		(fp_text user "Author: Antmicro"
			(at -1.276 4.7 180)
			(layer "F.Fab")
			(effects
				(font
					(size 0.7 0.7)
					(thickness 0.15)
				)
				(justify left bottom)
			)
		)
		(fp_text user "${REFERENCE}"
			(at -1.276 3.499 180)
			(layer "F.Fab")
			(effects
				(font
					(size 0.7 0.7)
					(thickness 0.15)
				)
				(justify left bottom)
			)
		)
		(fp_text user "License: Apache-2.0"
			(at -1.276 5.9 180)
			(layer "F.Fab")
			(effects
				(font
					(size 0.7 0.7)
					(thickness 0.15)
				)
				(justify left bottom)
			)
		)
		(pad "1" smd roundrect
			(at -0.701 0 180)
			(size 0.5 0.6)
			(layers "F.Cu" "F.Mask" "F.Paste")
			(roundrect_rratio 0.25)
			(net 40 "+5V")
			(pinfunction "C")
			(pintype "passive")
		)
		(pad "2" smd roundrect
			(at 0.699 0 180)
			(size 0.5 0.6)
			(layers "F.Cu" "F.Mask" "F.Paste")
			(roundrect_rratio 0.25)
			(net 23 "GND")
			(pinfunction "A")
			(pintype "passive")
		)
	)
	(footprint "antmicro-footprints:C_0402_1005Metric"
		(layer "F.Cu")
		(at 136.850001 129.15 -90)
		(descr "Capacitor SMD 0402")
		(tags "capacitor SMD 0402")
		(property "Reference" "C100"
			(at -0.450004 -7.15 270)
			(layer "F.SilkS")
			(effects
				(font
					(size 0.7 0.7)
					(thickness 0.15)
				)
				(justify left bottom)
			)
		)
		(property "Value" "C_10u_0402"
			(at -1.022927 2.155213 270)
			(layer "F.Fab")
			(effects
				(font
					(size 0.7 0.7)
					(thickness 0.15)
				)
				(justify left bottom)
			)
		)
		(property "Datasheet" "https://www.yageo.com/en/Chart/Download/pdf/CC0402MRX5R5BB106"
			(at 0 0 270)
			(layer "F.Fab")
			(hide yes)
			(effects
				(font
					(size 1.27 1.27)
					(thickness 0.15)
				)
			)
		)
		(property "Description" "SMD Multilayer Ceramic Capacitor, 10 µF, 6.3 V, 0402 [1005 Metric], ± 20%, X5R, CC Series"
			(at 0 0 270)
			(layer "F.Fab")
			(hide yes)
			(effects
				(font
					(size 1.27 1.27)
					(thickness 0.15)
				)
			)
		)
		(property "MPN" "CC0402MRX5R5BB106"
			(at 0 0 270)
			(unlocked yes)
			(layer "F.Fab")
			(hide yes)
			(effects
				(font
					(size 1 1)
					(thickness 0.15)
				)
			)
		)
		(property "Manufacturer" "YAGEO"
			(at 0 0 270)
			(unlocked yes)
			(layer "F.Fab")
			(hide yes)
			(effects
				(font
					(size 1 1)
					(thickness 0.15)
				)
			)
		)
		(property "License" "Apache-2.0"
			(at 0 0 270)
			(unlocked yes)
			(layer "F.Fab")
			(hide yes)
			(effects
				(font
					(size 1 1)
					(thickness 0.15)
				)
			)
		)
		(property "Val" "10u"
			(at 0 0 270)
			(unlocked yes)
			(layer "F.Fab")
			(hide yes)
			(effects
				(font
					(size 1 1)
					(thickness 0.15)
				)
			)
		)
		(property "Voltage" ""
			(at 0 0 270)
			(unlocked yes)
			(layer "F.Fab")
			(hide yes)
			(effects
				(font
					(size 1 1)
					(thickness 0.15)
				)
			)
		)
		(property "Dielectric" ""
			(at 0 0 270)
			(unlocked yes)
			(layer "F.Fab")
			(hide yes)
			(effects
				(font
					(size 1 1)
					(thickness 0.15)
				)
			)
		)
		(property "Author" "Antmicro"
			(at 0 0 270)
			(unlocked yes)
			(layer "F.Fab")
			(hide yes)
			(effects
				(font
					(size 1 1)
					(thickness 0.15)
				)
			)
		)
		(sheetname "/TB Controller - Power/")
		(sheetfile "tb-power.kicad_sch")
		(attr smd)
		(fp_rect
			(start -0.925 -0.47)
			(end 0.925 0.47)
			(stroke
				(width 0.05)
				(type default)
			)
			(fill no)
			(layer "F.CrtYd")
		)
		(fp_line
			(start -0.494 0.248)
			(end -0.494 -0.25)
			(stroke
				(width 0.15)
				(type solid)
			)
			(layer "F.Fab")
		)
		(fp_line
			(start 0.504 0.248)
			(end -0.494 0.248)
			(stroke
				(width 0.15)
				(type solid)
			)
			(layer "F.Fab")
		)
		(fp_line
			(start -0.494 -0.25)
			(end 0.504 -0.25)
			(stroke
				(width 0.15)
				(type solid)
			)
			(layer "F.Fab")
		)
		(fp_line
			(start 0.504 -0.25)
			(end 0.504 0.248)
			(stroke
				(width 0.15)
				(type solid)
			)
			(layer "F.Fab")
		)
		(fp_text user "License: Apache-2.0"
			(at -0.939 5.799 270)
			(layer "F.Fab")
			(effects
				(font
					(size 0.7 0.7)
					(thickness 0.15)
				)
				(justify left bottom)
			)
		)
		(fp_text user "${REFERENCE}"
			(at -0.939 4.599 270)
			(layer "F.Fab")
			(effects
				(font
					(size 0.7 0.7)
					(thickness 0.15)
				)
				(justify left bottom)
			)
		)
		(fp_text user "Author: Antmicro"
			(at -0.939 3.399 270)
			(layer "F.Fab")
			(effects
				(font
					(size 0.7 0.7)
					(thickness 0.15)
				)
				(justify left bottom)
			)
		)
		(pad "1" smd roundrect
			(at -0.48 0 270)
			(size 0.59 0.64)
			(layers "F.Cu" "F.Mask" "F.Paste")
			(roundrect_rratio 0.25)
			(net 23 "GND")
			(pintype "passive")
		)
		(pad "2" smd roundrect
			(at 0.48 0 270)
			(size 0.59 0.64)
			(layers "F.Cu" "F.Mask" "F.Paste")
			(roundrect_rratio 0.25)
			(net 57 "+3V3_TB")
			(pintype "passive")
		)
	)
	(footprint "antmicro-footprints:C_0402_1005Metric"
		(layer "F.Cu")
		(at 156.5 46.9)
		(descr "Capacitor SMD 0402")
		(tags "capacitor SMD 0402")
		(property "Reference" "C317"
			(at -1.7 -0.5 0)
			(layer "F.SilkS")
			(effects
				(font
					(size 0.7 0.7)
					(thickness 0.15)
				)
				(justify left bottom)
			)
		)
		(property "Value" "C_100n_0402"
			(at -1.022927 2.155213 0)
			(layer "F.Fab")
			(effects
				(font
					(size 0.7 0.7)
					(thickness 0.15)
				)
				(justify left bottom)
			)
		)
		(property "Datasheet" "https://www.murata.com/products/productdetail?partno=GRM155R61H104KE14%23"
			(at 0 0 0)
			(layer "F.Fab")
			(hide yes)
			(effects
				(font
					(size 1.27 1.27)
					(thickness 0.15)
				)
			)
		)
		(property "Description" "SMD Multilayer Ceramic Capacitor, 0.1 µF, 50 V, 0402 [1005 Metric], ± 10%, X5R, GRM Series"
			(at 0 0 0)
			(layer "F.Fab")
			(hide yes)
			(effects
				(font
					(size 1.27 1.27)
					(thickness 0.15)
				)
			)
		)
		(property "Manufacturer" "Murata"
			(at 0 0 0)
			(unlocked yes)
			(layer "F.Fab")
			(hide yes)
			(effects
				(font
					(size 1 1)
					(thickness 0.15)
				)
			)
		)
		(property "MPN" "GRM155R61H104KE14D"
			(at 0 0 0)
			(unlocked yes)
			(layer "F.Fab")
			(hide yes)
			(effects
				(font
					(size 1 1)
					(thickness 0.15)
				)
			)
		)
		(property "Val" "100n"
			(at 0 0 0)
			(unlocked yes)
			(layer "F.Fab")
			(hide yes)
			(effects
				(font
					(size 1 1)
					(thickness 0.15)
				)
			)
		)
		(property "License" "Apache-2.0"
			(at 0 0 0)
			(unlocked yes)
			(layer "F.Fab")
			(hide yes)
			(effects
				(font
					(size 1 1)
					(thickness 0.15)
				)
			)
		)
		(property "Author" "Antmicro"
			(at 0 0 0)
			(unlocked yes)
			(layer "F.Fab")
			(hide yes)
			(effects
				(font
					(size 1 1)
					(thickness 0.15)
				)
			)
		)
		(property "Voltage" "50V"
			(at 0 0 0)
			(unlocked yes)
			(layer "F.Fab")
			(hide yes)
			(effects
				(font
					(size 1 1)
					(thickness 0.15)
				)
			)
		)
		(property "Dielectric" "X5R"
			(at 0 0 0)
			(unlocked yes)
			(layer "F.Fab")
			(hide yes)
			(effects
				(font
					(size 1 1)
					(thickness 0.15)
				)
			)
		)
		(sheetname "/Power input/")
		(sheetfile "power_input.kicad_sch")
		(attr smd)
		(fp_rect
			(start -0.925 -0.47)
			(end 0.925 0.47)
			(stroke
				(width 0.05)
				(type default)
			)
			(fill no)
			(layer "F.CrtYd")
		)
		(fp_line
			(start -0.494 -0.25)
			(end 0.504 -0.25)
			(stroke
				(width 0.15)
				(type solid)
			)
			(layer "F.Fab")
		)
		(fp_line
			(start -0.494 0.248)
			(end -0.494 -0.25)
			(stroke
				(width 0.15)
				(type solid)
			)
			(layer "F.Fab")
		)
		(fp_line
			(start 0.504 -0.25)
			(end 0.504 0.248)
			(stroke
				(width 0.15)
				(type solid)
			)
			(layer "F.Fab")
		)
		(fp_line
			(start 0.504 0.248)
			(end -0.494 0.248)
			(stroke
				(width 0.15)
				(type solid)
			)
			(layer "F.Fab")
		)
		(fp_text user "${REFERENCE}"
			(at -0.939 4.599 0)
			(layer "F.Fab")
			(effects
				(font
					(size 0.7 0.7)
					(thickness 0.15)
				)
				(justify left bottom)
			)
		)
		(fp_text user "License: Apache-2.0"
			(at -0.939 5.799 0)
			(layer "F.Fab")
			(effects
				(font
					(size 0.7 0.7)
					(thickness 0.15)
				)
				(justify left bottom)
			)
		)
		(fp_text user "Author: Antmicro"
			(at -0.939 3.399 0)
			(layer "F.Fab")
			(effects
				(font
					(size 0.7 0.7)
					(thickness 0.15)
				)
				(justify left bottom)
			)
		)
		(pad "1" smd roundrect
			(at -0.48 0)
			(size 0.59 0.64)
			(layers "F.Cu" "F.Mask" "F.Paste")
			(roundrect_rratio 0.25)
			(net 348 "/Power input/5V_PHASE")
			(pintype "passive")
		)
		(pad "2" smd roundrect
			(at 0.48 0)
			(size 0.59 0.64)
			(layers "F.Cu" "F.Mask" "F.Paste")
			(roundrect_rratio 0.25)
			(net 347 "/Power input/5V_BOOT")
			(pintype "passive")
		)
	)
)
